(kicad_pcb
	(version 20260206)
	(generator "pcbnew")
	(generator_version "10.0")
	(general
		(thickness 1.6)
		(legacy_teardrops no)
	)
	(paper "A4")
	(title_block
		(title "Wiwynn_Tioga_Pass_MB.brd")
		(comment 1 "Tioga Pass / footprint 190 of 4770 (U2D1), pads 1016-1121 of 3647")
	)
	(layers
		(0 "F.Cu" signal "TOP")
		(4 "In1.Cu" signal "L2GND")
		(6 "In2.Cu" signal "L3")
		(8 "In3.Cu" signal "L4GND")
		(10 "In4.Cu" signal "L5")
		(12 "In5.Cu" signal "L6GND")
		(14 "In6.Cu" signal "L7VCC")
		(16 "In7.Cu" signal "L8VCC")
		(18 "In8.Cu" signal "L9GND")
		(20 "In9.Cu" signal "L10")
		(22 "In10.Cu" signal "L11GND")
		(24 "In11.Cu" signal "L12")
		(26 "In12.Cu" signal "L13GND")
		(2 "B.Cu" signal "BOTTOM")
		(9 "F.Adhes" user "F.Adhesive")
		(11 "B.Adhes" user "B.Adhesive")
		(13 "F.Paste" user "Package Geometry/Pastemask Top")
		(15 "B.Paste" user "Package Geometry/Pastemask Bottom")
		(5 "F.SilkS" user "Ref Des/Silkscreen Top")
		(7 "B.SilkS" user "Ref Des/Silkscreen Bottom")
		(1 "F.Mask" user "Board Geometry/Soldermask Top")
		(3 "B.Mask" user "Board Geometry/Soldermask Bottom")
		(17 "Dwgs.User" user "User.Drawings")
		(19 "Cmts.User" user "User.Comments")
		(21 "Eco1.User" user "User.Eco1")
		(23 "Eco2.User" user "User.Eco2")
		(25 "Edge.Cuts" user "Board Geometry/Outline")
		(27 "Margin" user)
		(31 "F.CrtYd" user "Package Geometry/Place Bound Top")
		(29 "B.CrtYd" user "Package Geometry/Place Bound Bottom")
		(35 "F.Fab" user "Ref Des/Assembly Top")
		(33 "B.Fab" user "Ref Des/Assembly Bottom")
	)
	(footprint ""
		(layer "F.Cu")
		(at 104.99979 -76.550012 180)
		(property "Reference" "U2D1"
			(at 25.19299 30.484318 0)
			(unlocked yes)
			(layer "F.SilkS")
			(effects
				(font
					(size 0.7874 0.5842)
					(thickness 0.1524)
				)
			)
		)
		(property "Value" ""
			(at 0 0 180)
			(layer "F.Fab")
			(effects
				(font
					(size 1.27 1.27)
				)
			)
		)
		(duplicate_pad_numbers_are_jumpers no)
		(pad "BL8" smd circle
			(at -31.240984 -0.338074)
			(size 0.4318 0.4318)
			(layers "F.Cu" "F.Mask" "F.Paste")
			(net "TP_P3E_CPU1_PE2_RSR_RXN<14>")
		)
		(pad "BL10" smd circle
			(at -29.523944 -0.338074)
			(size 0.4318 0.4318)
			(layers "F.Cu" "F.Mask" "F.Paste")
			(net "GND")
		)
		(pad "BL12" smd circle
			(at -27.806904 -0.338074)
			(size 0.4318 0.4318)
			(layers "F.Cu" "F.Mask" "F.Paste")
			(net "GND")
		)
		(pad "BL14" smd circle
			(at -26.090118 -0.338074)
			(size 0.4318 0.4318)
			(layers "F.Cu" "F.Mask" "F.Paste")
			(net "PVCCMCP_CPU1")
		)
		(pad "BL16" smd circle
			(at -24.373078 -0.338074)
			(size 0.4318 0.4318)
			(layers "F.Cu" "F.Mask" "F.Paste")
			(net "VSENSE_PVCCMCP_CPU1_SKT_VRTN")
		)
		(pad "BL18" smd circle
			(at -22.656038 -0.338074)
			(size 0.4318 0.4318)
			(layers "F.Cu" "F.Mask" "F.Paste")
			(net "PVCCIOMCP_CPU1")
		)
		(pad "BL20" smd circle
			(at -20.938998 -0.338074)
			(size 0.4318 0.4318)
			(layers "F.Cu" "F.Mask" "F.Paste")
			(net "PVCCMCP_CPU1")
		)
		(pad "BL22" smd circle
			(at -19.221958 -0.338074)
			(size 0.4318 0.4318)
			(layers "F.Cu" "F.Mask" "F.Paste")
			(net "GND")
		)
		(pad "BL24" smd circle
			(at -17.504918 -0.338074)
			(size 0.4318 0.4318)
			(layers "F.Cu" "F.Mask" "F.Paste")
			(net "GND")
		)
		(pad "BL26" smd circle
			(at -15.787878 -0.338074)
			(size 0.4318 0.4318)
			(layers "F.Cu" "F.Mask" "F.Paste")
			(net "PVCCIO_CPU1")
		)
		(pad "BL60" smd circle
			(at 14.929612 -2.138426)
			(size 0.508 0.508)
			(layers "F.Cu" "F.Mask" "F.Paste")
			(net "PVCCIN_CPU1")
		)
		(pad "BL62" smd circle
			(at 16.646398 -2.138426)
			(size 0.4318 0.4318)
			(layers "F.Cu" "F.Mask" "F.Paste")
			(net "PVCCIN_CPU1")
		)
		(pad "BL64" smd circle
			(at 18.363438 -2.138426)
			(size 0.4318 0.4318)
			(layers "F.Cu" "F.Mask" "F.Paste")
			(net "GND")
		)
		(pad "BL66" smd circle
			(at 20.080478 -2.138426)
			(size 0.4318 0.4318)
			(layers "F.Cu" "F.Mask" "F.Paste")
			(net "GND")
		)
		(pad "BL68" smd circle
			(at 21.797518 -2.138426)
			(size 0.4318 0.4318)
			(layers "F.Cu" "F.Mask" "F.Paste")
			(net "GND")
		)
		(pad "BL70" smd circle
			(at 23.514558 -2.138426)
			(size 0.4318 0.4318)
			(layers "F.Cu" "F.Mask" "F.Paste")
			(net "GND")
		)
		(pad "BL72" smd circle
			(at 25.231598 -2.138426)
			(size 0.4318 0.4318)
			(layers "F.Cu" "F.Mask" "F.Paste")
			(net "GND")
		)
		(pad "BL74" smd circle
			(at 26.948384 -2.138426)
			(size 0.4318 0.4318)
			(layers "F.Cu" "F.Mask" "F.Paste")
			(net "GND")
		)
		(pad "BL76" smd circle
			(at 28.665424 -2.138426)
			(size 0.4318 0.4318)
			(layers "F.Cu" "F.Mask" "F.Paste")
			(net "GND")
		)
		(pad "BL78" smd circle
			(at 30.382464 -2.138426)
			(size 0.4318 0.4318)
			(layers "F.Cu" "F.Mask" "F.Paste")
			(net "GND")
		)
		(pad "BL80" smd circle
			(at 32.099504 -2.138426)
			(size 0.4318 0.4318)
			(layers "F.Cu" "F.Mask" "F.Paste")
			(net "GND")
		)
		(pad "BL82" smd circle
			(at 33.816544 -2.138426)
			(size 0.4318 0.4318)
			(layers "F.Cu" "F.Mask" "F.Paste")
			(net "GND")
		)
		(pad "BL84" smd custom
			(at 35.533584 -2.138426 270)
			(size 0.10795 0.10795)
			(layers "F.Cu" "F.Mask" "F.Paste")
			(net "PVCCIN_CPU1")
			(options
				(clearance outline)
				(anchor circle)
			)
			(primitives
				(gr_poly
					(pts
						(arc
							(start 0.2159 -0.0381)
							(mid 0 -0.254)
							(end -0.2159 -0.0381)
						)
						(arc
							(start -0.2159 0.0381)
							(mid 0 0.254)
							(end 0.2159 0.0381)
						)
					)
					(width 0)
					(fill yes)
				)
			)
		)
		(pad "BM3" smd custom
			(at -35.533584 0.156972 90)
			(size 0.10795 0.10795)
			(layers "F.Cu" "F.Mask" "F.Paste")
			(net "TP_P3E_CPU1_PE2_RSR_TXP<14>")
			(options
				(clearance outline)
				(anchor circle)
			)
			(primitives
				(gr_poly
					(pts
						(arc
							(start 0.2159 -0.0381)
							(mid 0 -0.254)
							(end -0.2159 -0.0381)
						)
						(arc
							(start -0.2159 0.0381)
							(mid 0 0.254)
							(end 0.2159 0.0381)
						)
					)
					(width 0)
					(fill yes)
				)
			)
		)
		(pad "BM5" smd circle
			(at -33.816544 0.156972)
			(size 0.4318 0.4318)
			(layers "F.Cu" "F.Mask" "F.Paste")
			(net "TP_P3E_CPU1_PE2_RSR_TXN<15>")
		)
		(pad "BM7" smd circle
			(at -32.099504 0.156972)
			(size 0.4318 0.4318)
			(layers "F.Cu" "F.Mask" "F.Paste")
			(net "TP_P3E_CPU1_PE2_RSR_RXP<13>")
		)
		(pad "BM9" smd circle
			(at -30.382464 0.156972)
			(size 0.4318 0.4318)
			(layers "F.Cu" "F.Mask" "F.Paste")
			(net "GND")
		)
		(pad "BM11" smd circle
			(at -28.665424 0.156972)
			(size 0.4318 0.4318)
			(layers "F.Cu" "F.Mask" "F.Paste")
			(net "PVCCIOMCP_CPU1")
		)
		(pad "BM13" smd circle
			(at -26.948384 0.156972)
			(size 0.4318 0.4318)
			(layers "F.Cu" "F.Mask" "F.Paste")
			(net "GND")
		)
		(pad "BM15" smd circle
			(at -25.231598 0.156972)
			(size 0.4318 0.4318)
			(layers "F.Cu" "F.Mask" "F.Paste")
			(net "GND")
		)
		(pad "BM17" smd circle
			(at -23.514558 0.156972)
			(size 0.4318 0.4318)
			(layers "F.Cu" "F.Mask" "F.Paste")
			(net "PVCCIOMCP_CPU1")
		)
		(pad "BM19" smd circle
			(at -21.797518 0.156972)
			(size 0.4318 0.4318)
			(layers "F.Cu" "F.Mask" "F.Paste")
			(net "PVCCMCP_CPU1")
		)
		(pad "BM21" smd circle
			(at -20.080478 0.156972)
			(size 0.4318 0.4318)
			(layers "F.Cu" "F.Mask" "F.Paste")
			(net "TP_CD_HFI1_CPU1_INT_N")
		)
		(pad "BM23" smd circle
			(at -18.363438 0.156972)
			(size 0.4318 0.4318)
			(layers "F.Cu" "F.Mask" "F.Paste")
			(net "TP_CD_HFI1_CPU1_LED_N")
		)
		(pad "BM25" smd circle
			(at -16.646398 0.156972)
			(size 0.4318 0.4318)
			(layers "F.Cu" "F.Mask" "F.Paste")
			(net "GND")
		)
		(pad "BM27" smd circle
			(at -14.929612 0.156972)
			(size 0.4318 0.4318)
			(layers "F.Cu" "F.Mask" "F.Paste")
			(net "PVCCIO_CPU1")
		)
		(pad "BM61" smd circle
			(at 15.787878 -1.643126)
			(size 0.4318 0.4318)
			(layers "F.Cu" "F.Mask" "F.Paste")
			(net "PVCCIN_CPU1")
		)
		(pad "BM63" smd circle
			(at 17.504918 -1.643126)
			(size 0.4318 0.4318)
			(layers "F.Cu" "F.Mask" "F.Paste")
			(net "PVCCIN_CPU1")
		)
		(pad "BM65" smd circle
			(at 19.221958 -1.643126)
			(size 0.4318 0.4318)
			(layers "F.Cu" "F.Mask" "F.Paste")
			(net "PVCCIN_CPU1")
		)
		(pad "BM67" smd circle
			(at 20.938998 -1.643126)
			(size 0.4318 0.4318)
			(layers "F.Cu" "F.Mask" "F.Paste")
			(net "PVCCIN_CPU1")
		)
		(pad "BM69" smd circle
			(at 22.656038 -1.643126)
			(size 0.4318 0.4318)
			(layers "F.Cu" "F.Mask" "F.Paste")
			(net "PVCCIN_CPU1")
		)
		(pad "BM71" smd circle
			(at 24.373078 -1.643126)
			(size 0.4318 0.4318)
			(layers "F.Cu" "F.Mask" "F.Paste")
			(net "PVCCIN_CPU1")
		)
		(pad "BM73" smd circle
			(at 26.090118 -1.643126)
			(size 0.4318 0.4318)
			(layers "F.Cu" "F.Mask" "F.Paste")
			(net "PVCCIN_CPU1")
		)
		(pad "BM75" smd circle
			(at 27.806904 -1.643126)
			(size 0.4318 0.4318)
			(layers "F.Cu" "F.Mask" "F.Paste")
			(net "PVCCIN_CPU1")
		)
		(pad "BM77" smd circle
			(at 29.523944 -1.643126)
			(size 0.4318 0.4318)
			(layers "F.Cu" "F.Mask" "F.Paste")
			(net "PVCCIN_CPU1")
		)
		(pad "BM79" smd circle
			(at 31.240984 -1.643126)
			(size 0.4318 0.4318)
			(layers "F.Cu" "F.Mask" "F.Paste")
			(net "PVCCIN_CPU1")
		)
		(pad "BM81" smd circle
			(at 32.958024 -1.643126)
			(size 0.4318 0.4318)
			(layers "F.Cu" "F.Mask" "F.Paste")
			(net "PVCCIN_CPU1")
		)
		(pad "BM83" smd circle
			(at 34.675064 -1.643126)
			(size 0.4318 0.4318)
			(layers "F.Cu" "F.Mask" "F.Paste")
			(net "PVCCIN_CPU1")
		)
		(pad "BN4" smd circle
			(at -34.675064 0.652526)
			(size 0.4318 0.4318)
			(layers "F.Cu" "F.Mask" "F.Paste")
			(net "TP_P3E_CPU1_PE2_RSR_TXP<13>")
		)
		(pad "BN6" smd circle
			(at -32.958024 0.652526)
			(size 0.4318 0.4318)
			(layers "F.Cu" "F.Mask" "F.Paste")
			(net "GND")
		)
		(pad "BN8" smd circle
			(at -31.240984 0.652526)
			(size 0.4318 0.4318)
			(layers "F.Cu" "F.Mask" "F.Paste")
			(net "TP_P3E_CPU1_PE2_RSR_RXN<13>")
		)
		(pad "BN10" smd circle
			(at -29.523944 0.652526)
			(size 0.4318 0.4318)
			(layers "F.Cu" "F.Mask" "F.Paste")
			(net "GND")
		)
		(pad "BN12" smd circle
			(at -27.806904 0.652526)
			(size 0.4318 0.4318)
			(layers "F.Cu" "F.Mask" "F.Paste")
			(net "PVCCIOMCP_CPU1")
		)
		(pad "BN14" smd circle
			(at -26.090118 0.652526)
			(size 0.4318 0.4318)
			(layers "F.Cu" "F.Mask" "F.Paste")
			(net "PVCCIOMCP_CPU1")
		)
		(pad "BN16" smd circle
			(at -24.373078 0.652526)
			(size 0.4318 0.4318)
			(layers "F.Cu" "F.Mask" "F.Paste")
			(net "VSENSE_PVCCMCP_CPU1_SKT_VSEN")
		)
		(pad "BN18" smd circle
			(at -22.656038 0.652526)
			(size 0.4318 0.4318)
			(layers "F.Cu" "F.Mask" "F.Paste")
			(net "PVCCIOMCP_CPU1")
		)
		(pad "BN20" smd circle
			(at -20.938998 0.652526)
			(size 0.4318 0.4318)
			(layers "F.Cu" "F.Mask" "F.Paste")
			(net "GND")
		)
		(pad "BN22" smd circle
			(at -19.221958 0.652526)
			(size 0.4318 0.4318)
			(layers "F.Cu" "F.Mask" "F.Paste")
			(net "TP_SMB_CPU1_CD_HFI0_I2CCLK")
		)
		(pad "BN24" smd circle
			(at -17.504918 0.652526)
			(size 0.4318 0.4318)
			(layers "F.Cu" "F.Mask" "F.Paste")
			(net "TP_RST_CPU1_CD_HFI0_N")
		)
		(pad "BN26" smd circle
			(at -15.787878 0.652526)
			(size 0.4318 0.4318)
			(layers "F.Cu" "F.Mask" "F.Paste")
			(net "GND")
		)
		(pad "BN60" smd circle
			(at 14.929612 -1.147572)
			(size 0.508 0.508)
			(layers "F.Cu" "F.Mask" "F.Paste")
			(net "PVCCIN_CPU1")
		)
		(pad "BN62" smd circle
			(at 16.646398 -1.147572)
			(size 0.4318 0.4318)
			(layers "F.Cu" "F.Mask" "F.Paste")
			(net "PVCCIN_CPU1")
		)
		(pad "BN64" smd circle
			(at 18.363438 -1.147572)
			(size 0.4318 0.4318)
			(layers "F.Cu" "F.Mask" "F.Paste")
			(net "PVCCIN_CPU1")
		)
		(pad "BN66" smd circle
			(at 20.080478 -1.147572)
			(size 0.4318 0.4318)
			(layers "F.Cu" "F.Mask" "F.Paste")
			(net "PVCCIN_CPU1")
		)
		(pad "BN68" smd circle
			(at 21.797518 -1.147572)
			(size 0.4318 0.4318)
			(layers "F.Cu" "F.Mask" "F.Paste")
			(net "PVCCIN_CPU1")
		)
		(pad "BN70" smd circle
			(at 23.514558 -1.147572)
			(size 0.4318 0.4318)
			(layers "F.Cu" "F.Mask" "F.Paste")
			(net "PVCCIN_CPU1")
		)
		(pad "BN72" smd circle
			(at 25.231598 -1.147572)
			(size 0.4318 0.4318)
			(layers "F.Cu" "F.Mask" "F.Paste")
			(net "PVCCIN_CPU1")
		)
		(pad "BN74" smd circle
			(at 26.948384 -1.147572)
			(size 0.4318 0.4318)
			(layers "F.Cu" "F.Mask" "F.Paste")
			(net "PVCCIN_CPU1")
		)
		(pad "BN76" smd circle
			(at 28.665424 -1.147572)
			(size 0.4318 0.4318)
			(layers "F.Cu" "F.Mask" "F.Paste")
			(net "PVCCIN_CPU1")
		)
		(pad "BN78" smd circle
			(at 30.382464 -1.147572)
			(size 0.4318 0.4318)
			(layers "F.Cu" "F.Mask" "F.Paste")
			(net "PVCCIN_CPU1")
		)
		(pad "BN80" smd circle
			(at 32.099504 -1.147572)
			(size 0.4318 0.4318)
			(layers "F.Cu" "F.Mask" "F.Paste")
			(net "PVCCIN_CPU1")
		)
		(pad "BN82" smd circle
			(at 33.816544 -1.147572)
			(size 0.4318 0.4318)
			(layers "F.Cu" "F.Mask" "F.Paste")
			(net "PVCCIN_CPU1")
		)
		(pad "BN84" smd custom
			(at 35.533584 -1.147572 270)
			(size 0.10795 0.10795)
			(layers "F.Cu" "F.Mask" "F.Paste")
			(net "PVCCIN_CPU1")
			(options
				(clearance outline)
				(anchor circle)
			)
			(primitives
				(gr_poly
					(pts
						(arc
							(start 0.2159 -0.0381)
							(mid 0 -0.254)
							(end -0.2159 -0.0381)
						)
						(arc
							(start -0.2159 0.0381)
							(mid 0 0.254)
							(end 0.2159 0.0381)
						)
					)
					(width 0)
					(fill yes)
				)
			)
		)
		(pad "BP3" smd custom
			(at -35.533584 1.147572 90)
			(size 0.10795 0.10795)
			(layers "F.Cu" "F.Mask" "F.Paste")
			(net "GND")
			(options
				(clearance outline)
				(anchor circle)
			)
			(primitives
				(gr_poly
					(pts
						(arc
							(start 0.2159 -0.0381)
							(mid 0 -0.254)
							(end -0.2159 -0.0381)
						)
						(arc
							(start -0.2159 0.0381)
							(mid 0 0.254)
							(end 0.2159 0.0381)
						)
					)
					(width 0)
					(fill yes)
				)
			)
		)
		(pad "BP5" smd circle
			(at -33.816544 1.147572)
			(size 0.4318 0.4318)
			(layers "F.Cu" "F.Mask" "F.Paste")
			(net "TP_P3E_CPU1_PE2_RSR_TXN<13>")
		)
		(pad "BP7" smd circle
			(at -32.099504 1.147572)
			(size 0.4318 0.4318)
			(layers "F.Cu" "F.Mask" "F.Paste")
			(net "TP_P3E_CPU1_PE2_RSR_RXP<11>")
		)
		(pad "BP9" smd circle
			(at -30.382464 1.147572)
			(size 0.4318 0.4318)
			(layers "F.Cu" "F.Mask" "F.Paste")
			(net "TP_P3E_CPU1_PE2_RSR_RXP<12>")
		)
		(pad "BP11" smd circle
			(at -28.665424 1.147572)
			(size 0.4318 0.4318)
			(layers "F.Cu" "F.Mask" "F.Paste")
			(net "PVCCIOMCP_CPU1")
		)
		(pad "BP13" smd circle
			(at -26.948384 1.147572)
			(size 0.4318 0.4318)
			(layers "F.Cu" "F.Mask" "F.Paste")
			(net "PVCCIOMCP_CPU1")
		)
		(pad "BP15" smd circle
			(at -25.231598 1.147572)
			(size 0.4318 0.4318)
			(layers "F.Cu" "F.Mask" "F.Paste")
			(net "PVCCIOMCP_CPU1")
		)
		(pad "BP17" smd circle
			(at -23.514558 1.147572)
			(size 0.4318 0.4318)
			(layers "F.Cu" "F.Mask" "F.Paste")
			(net "PVCCIOMCP_CPU1")
		)
		(pad "BP19" smd circle
			(at -21.797518 1.147572)
			(size 0.4318 0.4318)
			(layers "F.Cu" "F.Mask" "F.Paste")
			(net "TP_IRQ_CPU1_CD_HFI0_N")
		)
		(pad "BP21" smd circle
			(at -20.080478 1.147572)
			(size 0.4318 0.4318)
			(layers "F.Cu" "F.Mask" "F.Paste")
			(net "PVCCMCP_CPU1")
		)
		(pad "BP23" smd circle
			(at -18.363438 1.147572)
			(size 0.4318 0.4318)
			(layers "F.Cu" "F.Mask" "F.Paste")
			(net "TP_SMB_CPU1_CD_HFI0_I2CDAT")
		)
		(pad "BP25" smd circle
			(at -16.646398 1.147572)
			(size 0.4318 0.4318)
			(layers "F.Cu" "F.Mask" "F.Paste")
			(net "PVCCIO_CPU1")
		)
		(pad "BP27" smd circle
			(at -14.929612 1.147572)
			(size 0.4318 0.4318)
			(layers "F.Cu" "F.Mask" "F.Paste")
			(net "GND")
		)
		(pad "BP61" smd circle
			(at 15.787878 -0.652526)
			(size 0.4318 0.4318)
			(layers "F.Cu" "F.Mask" "F.Paste")
			(net "PVCCIN_CPU1")
		)
		(pad "BP63" smd circle
			(at 17.504918 -0.652526)
			(size 0.4318 0.4318)
			(layers "F.Cu" "F.Mask" "F.Paste")
			(net "PVCCIN_CPU1")
		)
		(pad "BP65" smd circle
			(at 19.221958 -0.652526)
			(size 0.4318 0.4318)
			(layers "F.Cu" "F.Mask" "F.Paste")
			(net "PVCCIN_CPU1")
		)
		(pad "BP67" smd circle
			(at 20.938998 -0.652526)
			(size 0.4318 0.4318)
			(layers "F.Cu" "F.Mask" "F.Paste")
			(net "PVCCIN_CPU1")
		)
		(pad "BP69" smd circle
			(at 22.656038 -0.652526)
			(size 0.4318 0.4318)
			(layers "F.Cu" "F.Mask" "F.Paste")
			(net "PVCCIN_CPU1")
		)
		(pad "BP71" smd circle
			(at 24.373078 -0.652526)
			(size 0.4318 0.4318)
			(layers "F.Cu" "F.Mask" "F.Paste")
			(net "PVCCIN_CPU1")
		)
		(pad "BP73" smd circle
			(at 26.090118 -0.652526)
			(size 0.4318 0.4318)
			(layers "F.Cu" "F.Mask" "F.Paste")
			(net "PVCCIN_CPU1")
		)
		(pad "BP75" smd circle
			(at 27.806904 -0.652526)
			(size 0.4318 0.4318)
			(layers "F.Cu" "F.Mask" "F.Paste")
			(net "PVCCIN_CPU1")
		)
		(pad "BP77" smd circle
			(at 29.523944 -0.652526)
			(size 0.4318 0.4318)
			(layers "F.Cu" "F.Mask" "F.Paste")
			(net "PVCCIN_CPU1")
		)
		(pad "BP79" smd circle
			(at 31.240984 -0.652526)
			(size 0.4318 0.4318)
			(layers "F.Cu" "F.Mask" "F.Paste")
			(net "PVCCIN_CPU1")
		)
		(pad "BP81" smd circle
			(at 32.958024 -0.652526)
			(size 0.4318 0.4318)
			(layers "F.Cu" "F.Mask" "F.Paste")
			(net "PVCCIN_CPU1")
		)
		(pad "BP83" smd circle
			(at 34.675064 -0.652526)
			(size 0.4318 0.4318)
			(layers "F.Cu" "F.Mask" "F.Paste")
			(net "PVCCIN_CPU1")
		)
		(pad "BR4" smd circle
			(at -34.675064 1.643126)
			(size 0.4318 0.4318)
			(layers "F.Cu" "F.Mask" "F.Paste")
			(net "TP_P3E_CPU1_PE2_RSR_TXP<12>")
		)
		(pad "BR6" smd circle
			(at -32.958024 1.643126)
			(size 0.4318 0.4318)
			(layers "F.Cu" "F.Mask" "F.Paste")
			(net "GND")
		)
		(pad "BR8" smd circle
			(at -31.240984 1.643126)
			(size 0.4318 0.4318)
			(layers "F.Cu" "F.Mask" "F.Paste")
			(net "TP_P3E_CPU1_PE2_RSR_RXN<12>")
		)
		(pad "BR10" smd circle
			(at -29.523944 1.643126)
			(size 0.4318 0.4318)
			(layers "F.Cu" "F.Mask" "F.Paste")
			(net "GND")
		)
		(pad "BR12" smd circle
			(at -27.806904 1.643126)
			(size 0.4318 0.4318)
			(layers "F.Cu" "F.Mask" "F.Paste")
			(net "PVCCIOMCP_CPU1")
		)
		(pad "BR14" smd circle
			(at -26.090118 1.643126)
			(size 0.4318 0.4318)
			(layers "F.Cu" "F.Mask" "F.Paste")
			(net "PVCCIOMCP_CPU1")
		)
		(pad "BR16" smd circle
			(at -24.373078 1.643126)
			(size 0.4318 0.4318)
			(layers "F.Cu" "F.Mask" "F.Paste")
			(net "GND")
		)
		(pad "BR18" smd circle
			(at -22.656038 1.643126)
			(size 0.4318 0.4318)
			(layers "F.Cu" "F.Mask" "F.Paste")
			(net "GND")
		)
	)
)
